# SCM (Grand Teton) — schematic netlist excerpt (pin names and nets, part order shuffled) for the footprints in the layout excerpt that follows; sources: Cadence DE-HDL packaged netlist, KiCad conversion of 12092022_DA0F0TMDCD0_F0T_Management_Board_D_brd_V3_OCP.brd

R359  Q_RES  120 1% CHIP  pkg 0402LF  page 20 : A = M_BMC_DDR4_MA<8> ; B = P1V2_AUX
C82  Q_CAP  0.1UF 25V 10% X7R  pkg 0402  page 16 : A = P1V2_AUX ; B = GND

(kicad_pcb
	(version 20260206)
	(generator "pcbnew")
	(generator_version "10.0")
	(general
		(thickness 1.6)
		(legacy_teardrops no)
	)
	(paper "A4")
	(title_block
		(title "12092022_DA0F0TMDCD0_F0T_Management_Board_D_brd_V3_OCP.brd")
		(comment 1 "Grand Teton / footprints 1439-1440 of 1440")
	)
	(layers
		(0 "F.Cu" signal "TOP")
		(4 "In1.Cu" signal "GND")
		(6 "In2.Cu" signal "IN1")
		(8 "In3.Cu" signal "GND1")
		(10 "In4.Cu" signal "IN2")
		(12 "In5.Cu" signal "VCC")
		(14 "In6.Cu" signal "VCC1")
		(16 "In7.Cu" signal "IN3")
		(18 "In8.Cu" signal "GND2")
		(20 "In9.Cu" signal "IN4")
		(22 "In10.Cu" signal "GND3")
		(2 "B.Cu" signal "BOTTOM")
		(9 "F.Adhes" user "F.Adhesive")
		(11 "B.Adhes" user "B.Adhesive")
		(13 "F.Paste" user "Package Geometry/Pastemask Top")
		(15 "B.Paste" user "Package Geometry/Pastemask Bottom")
		(5 "F.SilkS" user "Ref Des/Silkscreen Top")
		(7 "B.SilkS" user "Ref Des/Silkscreen Bottom")
		(1 "F.Mask" user "Board Geometry/Soldermask Top")
		(3 "B.Mask" user "Board Geometry/Soldermask Bottom")
		(17 "Dwgs.User" user "User.Drawings")
		(19 "Cmts.User" user "User.Comments")
		(21 "Eco1.User" user "User.Eco1")
		(23 "Eco2.User" user "User.Eco2")
		(25 "Edge.Cuts" user "Board Geometry/Outline")
		(27 "Margin" user)
		(31 "F.CrtYd" user "Package Geometry/Place Bound Top")
		(29 "B.CrtYd" user "Package Geometry/Place Bound Bottom")
		(35 "F.Fab" user "Ref Des/Assembly Top")
		(33 "B.Fab" user "Ref Des/Assembly Bottom")
	)
	(footprint ""
		(layer "B.Cu")
		(at 53.04282 -51.69662)
		(property "Reference" "C82"
			(at 0 0 0)
			(layer "B.SilkS")
			(hide yes)
			(effects
				(font
					(size 1.27 1.27)
				)
				(justify mirror)
			)
		)
		(property "Value" ""
			(at 0 0 0)
			(layer "B.Fab")
			(effects
				(font
					(size 1.27 1.27)
				)
				(justify mirror)
			)
		)
		(duplicate_pad_numbers_are_jumpers no)
		(fp_line
			(start -0.7874 -0.4064)
			(end -0.7874 0.4064)
			(stroke
				(width 0.1524)
				(type default)
			)
			(layer "B.SilkS")
		)
		(fp_line
			(start -0.7874 0.4064)
			(end 0.7874 0.4064)
			(stroke
				(width 0.1524)
				(type default)
			)
			(layer "B.SilkS")
		)
		(fp_line
			(start 0.7874 -0.4064)
			(end -0.7874 -0.4064)
			(stroke
				(width 0.1524)
				(type default)
			)
			(layer "B.SilkS")
		)
		(fp_line
			(start 0.7874 0.4064)
			(end 0.7874 -0.4064)
			(stroke
				(width 0.1524)
				(type default)
			)
			(layer "B.SilkS")
		)
		(fp_line
			(start -0.67945 -0.3048)
			(end -0.67945 0.3048)
			(stroke
				(width 0.1)
				(type default)
			)
			(layer "B.Fab")
		)
		(fp_line
			(start -0.67945 0.3048)
			(end -0.120396 0.3048)
			(stroke
				(width 0.1)
				(type default)
			)
			(layer "B.Fab")
		)
		(fp_line
			(start -0.12065 -0.3048)
			(end -0.67945 -0.3048)
			(stroke
				(width 0.1)
				(type default)
			)
			(layer "B.Fab")
		)
		(fp_line
			(start -0.12065 -0.2794)
			(end -0.12065 -0.3048)
			(stroke
				(width 0.1)
				(type default)
			)
			(layer "B.Fab")
		)
		(fp_line
			(start -0.120396 0.2794)
			(end 0.12065 0.2794)
			(stroke
				(width 0.1)
				(type default)
			)
			(layer "B.Fab")
		)
		(fp_line
			(start -0.120396 0.3048)
			(end -0.120396 0.2794)
			(stroke
				(width 0.1)
				(type default)
			)
			(layer "B.Fab")
		)
		(fp_line
			(start 0.12065 -0.305054)
			(end 0.12065 -0.2794)
			(stroke
				(width 0.1)
				(type default)
			)
			(layer "B.Fab")
		)
		(fp_line
			(start 0.12065 -0.2794)
			(end -0.12065 -0.2794)
			(stroke
				(width 0.1)
				(type default)
			)
			(layer "B.Fab")
		)
		(fp_line
			(start 0.12065 0.2794)
			(end 0.12065 0.3048)
			(stroke
				(width 0.1)
				(type default)
			)
			(layer "B.Fab")
		)
		(fp_line
			(start 0.12065 0.3048)
			(end 0.67945 0.3048)
			(stroke
				(width 0.1)
				(type default)
			)
			(layer "B.Fab")
		)
		(fp_line
			(start 0.67945 -0.305054)
			(end 0.12065 -0.305054)
			(stroke
				(width 0.1)
				(type default)
			)
			(layer "B.Fab")
		)
		(fp_line
			(start 0.67945 0.3048)
			(end 0.67945 -0.305054)
			(stroke
				(width 0.1)
				(type default)
			)
			(layer "B.Fab")
		)
		(pad "1" smd circle
			(at 0.40005 0 180)
			(size 0 0)
			(layers "B.Cu" "B.Mask" "B.Paste")
			(net "P1V2_AUX")
		)
		(pad "2" smd circle
			(at -0.40005 0 180)
			(size 0 0)
			(layers "B.Cu" "B.Mask" "B.Paste")
			(net "GND")
		)
	)
	(footprint ""
		(layer "B.Cu")
		(at 78.723744 -37.559488 90)
		(property "Reference" "R359"
			(at 0 0 90)
			(layer "B.SilkS")
			(hide yes)
			(effects
				(font
					(size 1.27 1.27)
				)
				(justify mirror)
			)
		)
		(property "Value" ""
			(at 0 0 90)
			(layer "B.Fab")
			(effects
				(font
					(size 1.27 1.27)
				)
				(justify mirror)
			)
		)
		(duplicate_pad_numbers_are_jumpers no)
		(fp_line
			(start 0.7874 -0.4064)
			(end -0.7874 -0.4064)
			(stroke
				(width 0.1524)
				(type default)
			)
			(layer "B.SilkS")
		)
		(fp_line
			(start -0.7874 -0.4064)
			(end -0.7874 0.4064)
			(stroke
				(width 0.1524)
				(type default)
			)
			(layer "B.SilkS")
		)
		(fp_line
			(start 0.7874 0.4064)
			(end 0.7874 -0.4064)
			(stroke
				(width 0.1524)
				(type default)
			)
			(layer "B.SilkS")
		)
		(fp_line
			(start -0.7874 0.4064)
			(end 0.7874 0.4064)
			(stroke
				(width 0.1524)
				(type default)
			)
			(layer "B.SilkS")
		)
		(fp_line
			(start 0.67945 -0.305054)
			(end 0.12065 -0.305054)
			(stroke
				(width 0.1)
				(type default)
			)
			(layer "B.Fab")
		)
		(fp_line
			(start 0.12065 -0.305054)
			(end 0.12065 -0.2794)
			(stroke
				(width 0.1)
				(type default)
			)
			(layer "B.Fab")
		)
		(fp_line
			(start -0.12065 -0.3048)
			(end -0.67945 -0.3048)
			(stroke
				(width 0.1)
				(type default)
			)
			(layer "B.Fab")
		)
		(fp_line
			(start -0.67945 -0.3048)
			(end -0.67945 0.3048)
			(stroke
				(width 0.1)
				(type default)
			)
			(layer "B.Fab")
		)
		(fp_line
			(start 0.12065 -0.2794)
			(end -0.12065 -0.2794)
			(stroke
				(width 0.1)
				(type default)
			)
			(layer "B.Fab")
		)
		(fp_line
			(start -0.12065 -0.2794)
			(end -0.12065 -0.3048)
			(stroke
				(width 0.1)
				(type default)
			)
			(layer "B.Fab")
		)
		(fp_line
			(start 0.12065 0.2794)
			(end 0.12065 0.3048)
			(stroke
				(width 0.1)
				(type default)
			)
			(layer "B.Fab")
		)
		(fp_line
			(start -0.120396 0.2794)
			(end 0.12065 0.2794)
			(stroke
				(width 0.1)
				(type default)
			)
			(layer "B.Fab")
		)
		(fp_line
			(start 0.67945 0.3048)
			(end 0.67945 -0.305054)
			(stroke
				(width 0.1)
				(type default)
			)
			(layer "B.Fab")
		)
		(fp_line
			(start 0.12065 0.3048)
			(end 0.67945 0.3048)
			(stroke
				(width 0.1)
				(type default)
			)
			(layer "B.Fab")
		)
		(fp_line
			(start -0.120396 0.3048)
			(end -0.120396 0.2794)
			(stroke
				(width 0.1)
				(type default)
			)
			(layer "B.Fab")
		)
		(fp_line
			(start -0.67945 0.3048)
			(end -0.120396 0.3048)
			(stroke
				(width 0.1)
				(type default)
			)
			(layer "B.Fab")
		)
		(pad "1" smd circle
			(at 0.40005 0 270)
			(size 0 0)
			(layers "B.Cu" "B.Mask" "B.Paste")
			(net "M_BMC_DDR4_MA<8>")
		)
		(pad "2" smd circle
			(at -0.40005 0 270)
			(size 0 0)
			(layers "B.Cu" "B.Mask" "B.Paste")
			(net "P1V2_AUX")
		)
	)
)
